(kicad_pcb
	(version 20260206)
	(generator "pcbnew")
	(generator_version "10.0")
	(general
		(thickness 1.6)
		(legacy_teardrops no)
	)
	(paper "A4")
	(title_block
		(title "01162023_DA0F0TEBIF0_F0T_Expander_BD_F_brd_V02_OCP.brd")
		(comment 1 "Grand Teton / footprints 6336-6341 of 9728")
	)
	(layers
		(0 "F.Cu" signal "TOP")
		(4 "In1.Cu" signal "GND")
		(6 "In2.Cu" signal "VCC")
		(8 "In3.Cu" signal "VCC1")
		(10 "In4.Cu" signal "GND1")
		(12 "In5.Cu" signal "IN1")
		(14 "In6.Cu" signal "GND2")
		(16 "In7.Cu" signal "IN2")
		(18 "In8.Cu" signal "GND3")
		(20 "In9.Cu" signal "IN3")
		(22 "In10.Cu" signal "GND4")
		(24 "In11.Cu" signal "IN4")
		(26 "In12.Cu" signal "GND5")
		(28 "In13.Cu" signal "IN5")
		(30 "In14.Cu" signal "GND6")
		(32 "In15.Cu" signal "IN6")
		(34 "In16.Cu" signal "GND7")
		(2 "B.Cu" signal "BOTTOM")
		(9 "F.Adhes" user "F.Adhesive")
		(11 "B.Adhes" user "B.Adhesive")
		(13 "F.Paste" user "Package Geometry/Pastemask Top")
		(15 "B.Paste" user "Package Geometry/Pastemask Bottom")
		(5 "F.SilkS" user "Ref Des/Silkscreen Top")
		(7 "B.SilkS" user "Ref Des/Silkscreen Bottom")
		(1 "F.Mask" user "Board Geometry/Soldermask Top")
		(3 "B.Mask" user "Board Geometry/Soldermask Bottom")
		(17 "Dwgs.User" user "User.Drawings")
		(19 "Cmts.User" user "User.Comments")
		(21 "Eco1.User" user "User.Eco1")
		(23 "Eco2.User" user "User.Eco2")
		(25 "Edge.Cuts" user "Board Geometry/Outline")
		(27 "Margin" user)
		(31 "F.CrtYd" user "Package Geometry/Place Bound Top")
		(29 "B.CrtYd" user "Package Geometry/Place Bound Bottom")
		(35 "F.Fab" user "Ref Des/Assembly Top")
		(33 "B.Fab" user "Ref Des/Assembly Bottom")
	)
	(footprint ""
		(layer "F.Cu")
		(at 232.428288 -97.258378 -90)
		(property "Reference" "R1018"
			(at 0 0 270)
			(layer "F.SilkS")
			(hide yes)
			(effects
				(font
					(size 1.27 1.27)
				)
			)
		)
		(property "Value" ""
			(at 0 0 270)
			(layer "F.Fab")
			(effects
				(font
					(size 1.27 1.27)
				)
			)
		)
		(duplicate_pad_numbers_are_jumpers no)
		(fp_line
			(start -0.7874 0.4064)
			(end -0.7874 -0.4064)
			(stroke
				(width 0.1524)
				(type default)
			)
			(layer "F.SilkS")
		)
		(fp_line
			(start 0.7874 0.4064)
			(end -0.7874 0.4064)
			(stroke
				(width 0.1524)
				(type default)
			)
			(layer "F.SilkS")
		)
		(fp_line
			(start -0.7874 -0.4064)
			(end 0.7874 -0.4064)
			(stroke
				(width 0.1524)
				(type default)
			)
			(layer "F.SilkS")
		)
		(fp_line
			(start 0.7874 -0.4064)
			(end 0.7874 0.4064)
			(stroke
				(width 0.1524)
				(type default)
			)
			(layer "F.SilkS")
		)
		(fp_line
			(start -0.67945 0.3048)
			(end -0.67945 -0.305054)
			(stroke
				(width 0.1)
				(type default)
			)
			(layer "F.Fab")
		)
		(fp_line
			(start -0.12065 0.3048)
			(end -0.67945 0.3048)
			(stroke
				(width 0.1)
				(type default)
			)
			(layer "F.Fab")
		)
		(fp_line
			(start 0.120396 0.3048)
			(end 0.120396 0.2794)
			(stroke
				(width 0.1)
				(type default)
			)
			(layer "F.Fab")
		)
		(fp_line
			(start 0.67945 0.3048)
			(end 0.120396 0.3048)
			(stroke
				(width 0.1)
				(type default)
			)
			(layer "F.Fab")
		)
		(fp_line
			(start -0.12065 0.2794)
			(end -0.12065 0.3048)
			(stroke
				(width 0.1)
				(type default)
			)
			(layer "F.Fab")
		)
		(fp_line
			(start 0.120396 0.2794)
			(end -0.12065 0.2794)
			(stroke
				(width 0.1)
				(type default)
			)
			(layer "F.Fab")
		)
		(fp_line
			(start -0.12065 -0.2794)
			(end 0.12065 -0.2794)
			(stroke
				(width 0.1)
				(type default)
			)
			(layer "F.Fab")
		)
		(fp_line
			(start 0.12065 -0.2794)
			(end 0.12065 -0.3048)
			(stroke
				(width 0.1)
				(type default)
			)
			(layer "F.Fab")
		)
		(fp_line
			(start 0.12065 -0.3048)
			(end 0.67945 -0.3048)
			(stroke
				(width 0.1)
				(type default)
			)
			(layer "F.Fab")
		)
		(fp_line
			(start 0.67945 -0.3048)
			(end 0.67945 0.3048)
			(stroke
				(width 0.1)
				(type default)
			)
			(layer "F.Fab")
		)
		(fp_line
			(start -0.67945 -0.305054)
			(end -0.12065 -0.305054)
			(stroke
				(width 0.1)
				(type default)
			)
			(layer "F.Fab")
		)
		(fp_line
			(start -0.12065 -0.305054)
			(end -0.12065 -0.2794)
			(stroke
				(width 0.1)
				(type default)
			)
			(layer "F.Fab")
		)
		(pad "1" smd circle
			(at -0.40005 0 270)
			(size 0 0)
			(layers "F.Cu" "F.Mask" "F.Paste")
			(net "P3V3_AUX")
		)
		(pad "2" smd circle
			(at 0.40005 0 270)
			(size 0 0)
			(layers "F.Cu" "F.Mask" "F.Paste")
			(net "PEX_USB_HUB_OVCUR4")
		)
	)
	(footprint ""
		(layer "F.Cu")
		(at 15.201392 -55.78475 -90)
		(property "Reference" "PD22"
			(at 1.02235 2.144522 90)
			(unlocked yes)
			(layer "F.SilkS")
			(effects
				(font
					(size 0.7874 0.5842)
					(thickness 0.1524)
				)
				(justify left)
			)
		)
		(property "Value" ""
			(at 0 0 270)
			(layer "F.Fab")
			(effects
				(font
					(size 1.27 1.27)
				)
			)
		)
		(duplicate_pad_numbers_are_jumpers no)
		(fp_line
			(start -3.400044 1.459992)
			(end -3.400044 -1.459992)
			(stroke
				(width 0.1524)
				(type default)
			)
			(layer "F.SilkS")
		)
		(fp_line
			(start 4.107942 1.459992)
			(end -3.400044 1.459992)
			(stroke
				(width 0.1524)
				(type default)
			)
			(layer "F.SilkS")
		)
		(fp_line
			(start -3.400044 -1.459992)
			(end 4.107942 -1.459992)
			(stroke
				(width 0.1524)
				(type default)
			)
			(layer "F.SilkS")
		)
		(fp_line
			(start 4.107942 -1.459992)
			(end 4.107942 1.459992)
			(stroke
				(width 0.1524)
				(type default)
			)
			(layer "F.SilkS")
		)
		(fp_poly
			(pts
				(xy 4.107942 -1.459992) (xy 4.107942 1.459992) (xy 3.308096 1.459992) (xy 3.308096 -1.459992)
			)
			(stroke
				(width 0)
				(type default)
			)
			(fill yes)
			(layer "F.SilkS")
		)
		(fp_line
			(start -2.29997 1.459992)
			(end -2.29997 -1.459992)
			(stroke
				(width 0.1)
				(type default)
			)
			(layer "F.Fab")
		)
		(fp_line
			(start 2.29997 1.459992)
			(end -2.29997 1.459992)
			(stroke
				(width 0.1)
				(type default)
			)
			(layer "F.Fab")
		)
		(fp_line
			(start -2.29997 -1.459992)
			(end 2.29997 -1.459992)
			(stroke
				(width 0.1)
				(type default)
			)
			(layer "F.Fab")
		)
		(fp_line
			(start 2.29997 -1.459992)
			(end 2.29997 1.459992)
			(stroke
				(width 0.1)
				(type default)
			)
			(layer "F.Fab")
		)
		(fp_text user "-"
			(at 5.4102 0.29845 90)
			(unlocked yes)
			(layer "F.SilkS")
			(effects
				(font
					(size 1.905 1.4224)
					(thickness 0.1524)
				)
				(justify left)
			)
		)
		(fp_text user "+"
			(at -4.7752 -0.12065 270)
			(unlocked yes)
			(layer "F.SilkS")
			(effects
				(font
					(size 1.905 1.4224)
					(thickness 0.1524)
				)
				(justify left)
			)
		)
		(fp_text user "-"
			(at 5.4102 0.29845 90)
			(unlocked yes)
			(layer "F.Fab")
			(effects
				(font
					(size 1.905 1.4224)
					(thickness 0.1524)
				)
				(justify left)
			)
		)
		(fp_text user "+"
			(at -4.7752 -0.12065 270)
			(unlocked yes)
			(layer "F.Fab")
			(effects
				(font
					(size 1.905 1.4224)
					(thickness 0.1524)
				)
				(justify left)
			)
		)
		(pad "A" smd rect
			(at -1.999996 0)
			(size 1.7018 2.5146)
			(layers "F.Cu" "F.Mask" "F.Paste")
			(net "GND")
		)
		(pad "C" smd rect
			(at 1.999996 0)
			(size 1.7018 2.5146)
			(layers "F.Cu" "F.Mask" "F.Paste")
			(net "P12V_SSD0_R")
		)
	)
	(footprint ""
		(layer "F.Cu")
		(at 207.854296 -228.833426 180)
		(property "Reference" "R5917"
			(at 0 0 180)
			(layer "F.SilkS")
			(hide yes)
			(effects
				(font
					(size 1.27 1.27)
				)
			)
		)
		(property "Value" ""
			(at 0 0 180)
			(layer "F.Fab")
			(effects
				(font
					(size 1.27 1.27)
				)
			)
		)
		(duplicate_pad_numbers_are_jumpers no)
		(fp_line
			(start 0.7874 0.4064)
			(end -0.7874 0.4064)
			(stroke
				(width 0.1524)
				(type default)
			)
			(layer "F.SilkS")
		)
		(fp_line
			(start 0.7874 -0.4064)
			(end 0.7874 0.4064)
			(stroke
				(width 0.1524)
				(type default)
			)
			(layer "F.SilkS")
		)
		(fp_line
			(start -0.7874 0.4064)
			(end -0.7874 -0.4064)
			(stroke
				(width 0.1524)
				(type default)
			)
			(layer "F.SilkS")
		)
		(fp_line
			(start -0.7874 -0.4064)
			(end 0.7874 -0.4064)
			(stroke
				(width 0.1524)
				(type default)
			)
			(layer "F.SilkS")
		)
		(fp_line
			(start 0.67945 0.3048)
			(end 0.120396 0.3048)
			(stroke
				(width 0.1)
				(type default)
			)
			(layer "F.Fab")
		)
		(fp_line
			(start 0.67945 -0.3048)
			(end 0.67945 0.3048)
			(stroke
				(width 0.1)
				(type default)
			)
			(layer "F.Fab")
		)
		(fp_line
			(start 0.12065 -0.2794)
			(end 0.12065 -0.3048)
			(stroke
				(width 0.1)
				(type default)
			)
			(layer "F.Fab")
		)
		(fp_line
			(start 0.12065 -0.3048)
			(end 0.67945 -0.3048)
			(stroke
				(width 0.1)
				(type default)
			)
			(layer "F.Fab")
		)
		(fp_line
			(start 0.120396 0.3048)
			(end 0.120396 0.2794)
			(stroke
				(width 0.1)
				(type default)
			)
			(layer "F.Fab")
		)
		(fp_line
			(start 0.120396 0.2794)
			(end -0.12065 0.2794)
			(stroke
				(width 0.1)
				(type default)
			)
			(layer "F.Fab")
		)
		(fp_line
			(start -0.12065 0.3048)
			(end -0.67945 0.3048)
			(stroke
				(width 0.1)
				(type default)
			)
			(layer "F.Fab")
		)
		(fp_line
			(start -0.12065 0.2794)
			(end -0.12065 0.3048)
			(stroke
				(width 0.1)
				(type default)
			)
			(layer "F.Fab")
		)
		(fp_line
			(start -0.12065 -0.2794)
			(end 0.12065 -0.2794)
			(stroke
				(width 0.1)
				(type default)
			)
			(layer "F.Fab")
		)
		(fp_line
			(start -0.12065 -0.305054)
			(end -0.12065 -0.2794)
			(stroke
				(width 0.1)
				(type default)
			)
			(layer "F.Fab")
		)
		(fp_line
			(start -0.67945 0.3048)
			(end -0.67945 -0.305054)
			(stroke
				(width 0.1)
				(type default)
			)
			(layer "F.Fab")
		)
		(fp_line
			(start -0.67945 -0.305054)
			(end -0.12065 -0.305054)
			(stroke
				(width 0.1)
				(type default)
			)
			(layer "F.Fab")
		)
		(pad "1" smd circle
			(at -0.40005 0 180)
			(size 0 0)
			(layers "F.Cu" "F.Mask" "F.Paste")
			(net "GND")
		)
		(pad "2" smd circle
			(at 0.40005 0 180)
			(size 0 0)
			(layers "F.Cu" "F.Mask" "F.Paste")
			(net "PD_BIC_UART_SEL")
		)
	)
	(footprint ""
		(layer "F.Cu")
		(at 266.054078 -307.415438 45)
		(property "Reference" "R1352"
			(at 0 0 45)
			(layer "F.SilkS")
			(hide yes)
			(effects
				(font
					(size 1.27 1.27)
				)
			)
		)
		(property "Value" ""
			(at 0 0 45)
			(layer "F.Fab")
			(effects
				(font
					(size 1.27 1.27)
				)
			)
		)
		(duplicate_pad_numbers_are_jumpers no)
		(fp_line
			(start -0.787389 -0.406267)
			(end 0.787389 -0.406267)
			(stroke
				(width 0.1524)
				(type default)
			)
			(layer "F.SilkS")
		)
		(fp_line
			(start -0.787389 0.406267)
			(end -0.787389 -0.406267)
			(stroke
				(width 0.1524)
				(type default)
			)
			(layer "F.SilkS")
		)
		(fp_line
			(start 0.787389 -0.406267)
			(end 0.787389 0.406267)
			(stroke
				(width 0.1524)
				(type default)
			)
			(layer "F.SilkS")
		)
		(fp_line
			(start 0.787389 0.406267)
			(end -0.787389 0.406267)
			(stroke
				(width 0.1524)
				(type default)
			)
			(layer "F.SilkS")
		)
		(fp_line
			(start -0.679446 -0.305149)
			(end -0.120695 -0.304969)
			(stroke
				(width 0.1)
				(type default)
			)
			(layer "F.Fab")
		)
		(fp_line
			(start -0.120695 -0.304969)
			(end -0.120695 -0.279466)
			(stroke
				(width 0.1)
				(type default)
			)
			(layer "F.Fab")
		)
		(fp_line
			(start -0.120695 -0.279466)
			(end 0.120695 -0.279466)
			(stroke
				(width 0.1)
				(type default)
			)
			(layer "F.Fab")
		)
		(fp_line
			(start -0.679446 0.30479)
			(end -0.679446 -0.305149)
			(stroke
				(width 0.1)
				(type default)
			)
			(layer "F.Fab")
		)
		(fp_line
			(start 0.120515 -0.30479)
			(end 0.679446 -0.30479)
			(stroke
				(width 0.1)
				(type default)
			)
			(layer "F.Fab")
		)
		(fp_line
			(start 0.120695 -0.279466)
			(end 0.120515 -0.30479)
			(stroke
				(width 0.1)
				(type default)
			)
			(layer "F.Fab")
		)
		(fp_line
			(start -0.120695 0.279466)
			(end -0.120515 0.30479)
			(stroke
				(width 0.1)
				(type default)
			)
			(layer "F.Fab")
		)
		(fp_line
			(start -0.120515 0.30479)
			(end -0.679446 0.30479)
			(stroke
				(width 0.1)
				(type default)
			)
			(layer "F.Fab")
		)
		(fp_line
			(start 0.679446 -0.30479)
			(end 0.679446 0.30479)
			(stroke
				(width 0.1)
				(type default)
			)
			(layer "F.Fab")
		)
		(fp_line
			(start 0.120335 0.279466)
			(end -0.120695 0.279466)
			(stroke
				(width 0.1)
				(type default)
			)
			(layer "F.Fab")
		)
		(fp_line
			(start 0.120515 0.30479)
			(end 0.120335 0.279466)
			(stroke
				(width 0.1)
				(type default)
			)
			(layer "F.Fab")
		)
		(fp_line
			(start 0.679446 0.30479)
			(end 0.120515 0.30479)
			(stroke
				(width 0.1)
				(type default)
			)
			(layer "F.Fab")
		)
		(pad "1" smd circle
			(at -0.40005 0 45)
			(size 0 0)
			(layers "F.Cu" "F.Mask" "F.Paste")
			(net "GND")
		)
		(pad "2" smd circle
			(at 0.40005 0 45)
			(size 0 0)
			(layers "F.Cu" "F.Mask" "F.Paste")
			(net "PEX2_DBG_MODE1")
		)
	)
	(footprint ""
		(layer "F.Cu")
		(at 29.88818 -260.84911 -90)
		(property "Reference" "C3033"
			(at 0 0 270)
			(layer "F.SilkS")
			(hide yes)
			(effects
				(font
					(size 1.27 1.27)
				)
			)
		)
		(property "Value" ""
			(at 0 0 270)
			(layer "F.Fab")
			(effects
				(font
					(size 1.27 1.27)
				)
			)
		)
		(duplicate_pad_numbers_are_jumpers no)
		(fp_line
			(start -1.2954 0.5842)
			(end -1.2954 -0.5842)
			(stroke
				(width 0.1524)
				(type default)
			)
			(layer "F.SilkS")
		)
		(fp_line
			(start 1.2954 0.5842)
			(end -1.2954 0.5842)
			(stroke
				(width 0.1524)
				(type default)
			)
			(layer "F.SilkS")
		)
		(fp_line
			(start -1.2954 -0.5842)
			(end 1.2954 -0.5842)
			(stroke
				(width 0.1524)
				(type default)
			)
			(layer "F.SilkS")
		)
		(fp_line
			(start 1.2954 -0.5842)
			(end 1.2954 0.5842)
			(stroke
				(width 0.1524)
				(type default)
			)
			(layer "F.SilkS")
		)
		(fp_line
			(start -0.8636 0.4572)
			(end -0.8636 0.4064)
			(stroke
				(width 0.1)
				(type default)
			)
			(layer "F.Fab")
		)
		(fp_line
			(start 0.8636 0.4572)
			(end -0.8636 0.4572)
			(stroke
				(width 0.1)
				(type default)
			)
			(layer "F.Fab")
		)
		(fp_line
			(start -1.1938 0.4064)
			(end -1.1938 -0.4064)
			(stroke
				(width 0.1)
				(type default)
			)
			(layer "F.Fab")
		)
		(fp_line
			(start -0.8636 0.4064)
			(end -1.1938 0.4064)
			(stroke
				(width 0.1)
				(type default)
			)
			(layer "F.Fab")
		)
		(fp_line
			(start 0.8636 0.4064)
			(end 0.8636 0.4572)
			(stroke
				(width 0.1)
				(type default)
			)
			(layer "F.Fab")
		)
		(fp_line
			(start 1.1938 0.4064)
			(end 0.8636 0.4064)
			(stroke
				(width 0.1)
				(type default)
			)
			(layer "F.Fab")
		)
		(fp_line
			(start -1.1938 -0.4064)
			(end -0.8636 -0.4064)
			(stroke
				(width 0.1)
				(type default)
			)
			(layer "F.Fab")
		)
		(fp_line
			(start -0.8636 -0.4064)
			(end -0.8636 -0.4572)
			(stroke
				(width 0.1)
				(type default)
			)
			(layer "F.Fab")
		)
		(fp_line
			(start 0.8636 -0.4064)
			(end 1.1938 -0.4064)
			(stroke
				(width 0.1)
				(type default)
			)
			(layer "F.Fab")
		)
		(fp_line
			(start 1.1938 -0.4064)
			(end 1.1938 0.4064)
			(stroke
				(width 0.1)
				(type default)
			)
			(layer "F.Fab")
		)
		(fp_line
			(start -0.8636 -0.4572)
			(end 0.8636 -0.4572)
			(stroke
				(width 0.1)
				(type default)
			)
			(layer "F.Fab")
		)
		(fp_line
			(start 0.8636 -0.4572)
			(end 0.8636 -0.4064)
			(stroke
				(width 0.1)
				(type default)
			)
			(layer "F.Fab")
		)
		(pad "1" smd rect
			(at -0.7366 0 180)
			(size 0.7112 0.8128)
			(layers "F.Cu" "F.Mask" "F.Paste")
			(net "P1V8_PLL0_PEX0")
		)
		(pad "2" smd rect
			(at 0.7366 0 180)
			(size 0.7112 0.8128)
			(layers "F.Cu" "F.Mask" "F.Paste")
			(net "GND")
		)
	)
	(footprint ""
		(layer "F.Cu")
		(at 365.506 -212.979 180)
		(property "Reference" "R4635"
			(at 0 0 180)
			(layer "F.SilkS")
			(hide yes)
			(effects
				(font
					(size 1.27 1.27)
				)
			)
		)
		(property "Value" ""
			(at 0 0 180)
			(layer "F.Fab")
			(effects
				(font
					(size 1.27 1.27)
				)
			)
		)
		(duplicate_pad_numbers_are_jumpers no)
		(fp_line
			(start 0.7874 0.4064)
			(end -0.7874 0.4064)
			(stroke
				(width 0.1524)
				(type default)
			)
			(layer "F.SilkS")
		)
		(fp_line
			(start 0.7874 -0.4064)
			(end 0.7874 0.4064)
			(stroke
				(width 0.1524)
				(type default)
			)
			(layer "F.SilkS")
		)
		(fp_line
			(start -0.7874 0.4064)
			(end -0.7874 -0.4064)
			(stroke
				(width 0.1524)
				(type default)
			)
			(layer "F.SilkS")
		)
		(fp_line
			(start -0.7874 -0.4064)
			(end 0.7874 -0.4064)
			(stroke
				(width 0.1524)
				(type default)
			)
			(layer "F.SilkS")
		)
		(fp_line
			(start 0.67945 0.3048)
			(end 0.120396 0.3048)
			(stroke
				(width 0.1)
				(type default)
			)
			(layer "F.Fab")
		)
		(fp_line
			(start 0.67945 -0.3048)
			(end 0.67945 0.3048)
			(stroke
				(width 0.1)
				(type default)
			)
			(layer "F.Fab")
		)
		(fp_line
			(start 0.12065 -0.2794)
			(end 0.12065 -0.3048)
			(stroke
				(width 0.1)
				(type default)
			)
			(layer "F.Fab")
		)
		(fp_line
			(start 0.12065 -0.3048)
			(end 0.67945 -0.3048)
			(stroke
				(width 0.1)
				(type default)
			)
			(layer "F.Fab")
		)
		(fp_line
			(start 0.120396 0.3048)
			(end 0.120396 0.2794)
			(stroke
				(width 0.1)
				(type default)
			)
			(layer "F.Fab")
		)
		(fp_line
			(start 0.120396 0.2794)
			(end -0.12065 0.2794)
			(stroke
				(width 0.1)
				(type default)
			)
			(layer "F.Fab")
		)
		(fp_line
			(start -0.12065 0.3048)
			(end -0.67945 0.3048)
			(stroke
				(width 0.1)
				(type default)
			)
			(layer "F.Fab")
		)
		(fp_line
			(start -0.12065 0.2794)
			(end -0.12065 0.3048)
			(stroke
				(width 0.1)
				(type default)
			)
			(layer "F.Fab")
		)
		(fp_line
			(start -0.12065 -0.2794)
			(end 0.12065 -0.2794)
			(stroke
				(width 0.1)
				(type default)
			)
			(layer "F.Fab")
		)
		(fp_line
			(start -0.12065 -0.305054)
			(end -0.12065 -0.2794)
			(stroke
				(width 0.1)
				(type default)
			)
			(layer "F.Fab")
		)
		(fp_line
			(start -0.67945 0.3048)
			(end -0.67945 -0.305054)
			(stroke
				(width 0.1)
				(type default)
			)
			(layer "F.Fab")
		)
		(fp_line
			(start -0.67945 -0.305054)
			(end -0.12065 -0.305054)
			(stroke
				(width 0.1)
				(type default)
			)
			(layer "F.Fab")
		)
		(pad "1" smd circle
			(at -0.40005 0 180)
			(size 0 0)
			(layers "F.Cu" "F.Mask" "F.Paste")
			(net "GND")
		)
		(pad "2" smd circle
			(at 0.40005 0 180)
			(size 0 0)
			(layers "F.Cu" "F.Mask" "F.Paste")
			(net "PCA9555_0_PEX0_A2")
		)
	)
)
